# T6G (Grand Teton) — schematic netlist excerpt (pin names and nets, part order shuffled) for the footprints in the layout excerpt that follows; sources: Cadence DE-HDL packaged netlist, KiCad conversion of 04192023_DAF0TMB3IC0_F0TG_MB_C_brd_V02_OCP.brd

R512  Q_RES  2.2K 5% CHIP  pkg 0402LF  page 54 : A = P3V3_AUX ; B = CPU1_CORETYPE2
C617  Q_CAP  0.1UF 10V 10% X7S  pkg C0201  page 290 : A = P0V9_CPU0_RT1_2A_2D ; B = GND
C2547  Q_CAP  22UF 4V 20% X6S  pkg C0402  page 70 : A = PVDDCR_SOC_P0 ; B = GND

(kicad_pcb
	(version 20260206)
	(generator "pcbnew")
	(generator_version "10.0")
	(general
		(thickness 1.6)
		(legacy_teardrops no)
	)
	(paper "A4")
	(title_block
		(title "04192023_DAF0TMB3IC0_F0TG_MB_C_brd_V02_OCP.brd")
		(comment 1 "Grand Teton / footprints 7517-7519 of 8354")
	)
	(layers
		(0 "F.Cu" signal "TOP")
		(4 "In1.Cu" signal "GND")
		(6 "In2.Cu" signal "IN1")
		(8 "In3.Cu" signal "GND1")
		(10 "In4.Cu" signal "IN2")
		(12 "In5.Cu" signal "GND2")
		(14 "In6.Cu" signal "IN3")
		(16 "In7.Cu" signal "GND3")
		(18 "In8.Cu" signal "VCC")
		(20 "In9.Cu" signal "VCC1")
		(22 "In10.Cu" signal "GND4")
		(24 "In11.Cu" signal "IN4")
		(26 "In12.Cu" signal "GND5")
		(28 "In13.Cu" signal "IN5")
		(30 "In14.Cu" signal "GND6")
		(32 "In15.Cu" signal "IN6")
		(34 "In16.Cu" signal "GND7")
		(2 "B.Cu" signal "BOTTOM")
		(9 "F.Adhes" user "F.Adhesive")
		(11 "B.Adhes" user "B.Adhesive")
		(13 "F.Paste" user "Package Geometry/Pastemask Top")
		(15 "B.Paste" user "Package Geometry/Pastemask Bottom")
		(5 "F.SilkS" user "Ref Des/Silkscreen Top")
		(7 "B.SilkS" user "Ref Des/Silkscreen Bottom")
		(1 "F.Mask" user "Board Geometry/Soldermask Top")
		(3 "B.Mask" user "Board Geometry/Soldermask Bottom")
		(17 "Dwgs.User" user "User.Drawings")
		(19 "Cmts.User" user "User.Comments")
		(21 "Eco1.User" user "User.Eco1")
		(23 "Eco2.User" user "User.Eco2")
		(25 "Edge.Cuts" user "Board Geometry/Outline")
		(27 "Margin" user)
		(31 "F.CrtYd" user "Package Geometry/Place Bound Top")
		(29 "B.CrtYd" user "Package Geometry/Place Bound Bottom")
		(35 "F.Fab" user "Ref Des/Assembly Top")
		(33 "B.Fab" user "Ref Des/Assembly Bottom")
	)
	(footprint ""
		(layer "B.Cu")
		(at 356.565962 -256.012188 -90)
		(property "Reference" "C2547"
			(at 0 0 90)
			(layer "B.SilkS")
			(hide yes)
			(effects
				(font
					(size 1.27 1.27)
				)
				(justify mirror)
			)
		)
		(property "Value" ""
			(at 0 0 90)
			(layer "B.Fab")
			(effects
				(font
					(size 1.27 1.27)
				)
				(justify mirror)
			)
		)
		(duplicate_pad_numbers_are_jumpers no)
		(fp_line
			(start -0.7874 0.4064)
			(end 0.7874 0.4064)
			(stroke
				(width 0.1524)
				(type default)
			)
			(layer "B.SilkS")
		)
		(fp_line
			(start 0.7874 0.4064)
			(end 0.7874 -0.4064)
			(stroke
				(width 0.1524)
				(type default)
			)
			(layer "B.SilkS")
		)
		(fp_line
			(start -0.7874 -0.4064)
			(end -0.7874 0.4064)
			(stroke
				(width 0.1524)
				(type default)
			)
			(layer "B.SilkS")
		)
		(fp_line
			(start 0.7874 -0.4064)
			(end -0.7874 -0.4064)
			(stroke
				(width 0.1524)
				(type default)
			)
			(layer "B.SilkS")
		)
		(fp_line
			(start -0.67945 0.3048)
			(end -0.120396 0.3048)
			(stroke
				(width 0.1)
				(type default)
			)
			(layer "B.Fab")
		)
		(fp_line
			(start -0.120396 0.3048)
			(end -0.120396 0.2794)
			(stroke
				(width 0.1)
				(type default)
			)
			(layer "B.Fab")
		)
		(fp_line
			(start 0.12065 0.3048)
			(end 0.67945 0.3048)
			(stroke
				(width 0.1)
				(type default)
			)
			(layer "B.Fab")
		)
		(fp_line
			(start 0.67945 0.3048)
			(end 0.67945 -0.305054)
			(stroke
				(width 0.1)
				(type default)
			)
			(layer "B.Fab")
		)
		(fp_line
			(start -0.120396 0.2794)
			(end 0.12065 0.2794)
			(stroke
				(width 0.1)
				(type default)
			)
			(layer "B.Fab")
		)
		(fp_line
			(start 0.12065 0.2794)
			(end 0.12065 0.3048)
			(stroke
				(width 0.1)
				(type default)
			)
			(layer "B.Fab")
		)
		(fp_line
			(start -0.12065 -0.2794)
			(end -0.12065 -0.3048)
			(stroke
				(width 0.1)
				(type default)
			)
			(layer "B.Fab")
		)
		(fp_line
			(start 0.12065 -0.2794)
			(end -0.12065 -0.2794)
			(stroke
				(width 0.1)
				(type default)
			)
			(layer "B.Fab")
		)
		(fp_line
			(start -0.67945 -0.3048)
			(end -0.67945 0.3048)
			(stroke
				(width 0.1)
				(type default)
			)
			(layer "B.Fab")
		)
		(fp_line
			(start -0.12065 -0.3048)
			(end -0.67945 -0.3048)
			(stroke
				(width 0.1)
				(type default)
			)
			(layer "B.Fab")
		)
		(fp_line
			(start 0.12065 -0.305054)
			(end 0.12065 -0.2794)
			(stroke
				(width 0.1)
				(type default)
			)
			(layer "B.Fab")
		)
		(fp_line
			(start 0.67945 -0.305054)
			(end 0.12065 -0.305054)
			(stroke
				(width 0.1)
				(type default)
			)
			(layer "B.Fab")
		)
		(pad "1" smd circle
			(at 0.40005 0 90)
			(size 0 0)
			(layers "B.Cu" "B.Mask" "B.Paste")
			(net "PVDDCR_SOC_P0")
		)
		(pad "2" smd circle
			(at -0.40005 0 90)
			(size 0 0)
			(layers "B.Cu" "B.Mask" "B.Paste")
			(net "GND")
		)
	)
	(footprint ""
		(layer "B.Cu")
		(at 68.318634 -203.501752 -90)
		(property "Reference" "R512"
			(at 0 0 90)
			(layer "B.SilkS")
			(hide yes)
			(effects
				(font
					(size 1.27 1.27)
				)
				(justify mirror)
			)
		)
		(property "Value" ""
			(at 0 0 90)
			(layer "B.Fab")
			(effects
				(font
					(size 1.27 1.27)
				)
				(justify mirror)
			)
		)
		(duplicate_pad_numbers_are_jumpers no)
		(fp_line
			(start -0.7874 0.4064)
			(end 0.7874 0.4064)
			(stroke
				(width 0.1524)
				(type default)
			)
			(layer "B.SilkS")
		)
		(fp_line
			(start 0.7874 0.4064)
			(end 0.7874 -0.4064)
			(stroke
				(width 0.1524)
				(type default)
			)
			(layer "B.SilkS")
		)
		(fp_line
			(start -0.7874 -0.4064)
			(end -0.7874 0.4064)
			(stroke
				(width 0.1524)
				(type default)
			)
			(layer "B.SilkS")
		)
		(fp_line
			(start 0.7874 -0.4064)
			(end -0.7874 -0.4064)
			(stroke
				(width 0.1524)
				(type default)
			)
			(layer "B.SilkS")
		)
		(fp_line
			(start -0.67945 0.3048)
			(end -0.120396 0.3048)
			(stroke
				(width 0.1)
				(type default)
			)
			(layer "B.Fab")
		)
		(fp_line
			(start -0.120396 0.3048)
			(end -0.120396 0.2794)
			(stroke
				(width 0.1)
				(type default)
			)
			(layer "B.Fab")
		)
		(fp_line
			(start 0.12065 0.3048)
			(end 0.67945 0.3048)
			(stroke
				(width 0.1)
				(type default)
			)
			(layer "B.Fab")
		)
		(fp_line
			(start 0.67945 0.3048)
			(end 0.67945 -0.305054)
			(stroke
				(width 0.1)
				(type default)
			)
			(layer "B.Fab")
		)
		(fp_line
			(start -0.120396 0.2794)
			(end 0.12065 0.2794)
			(stroke
				(width 0.1)
				(type default)
			)
			(layer "B.Fab")
		)
		(fp_line
			(start 0.12065 0.2794)
			(end 0.12065 0.3048)
			(stroke
				(width 0.1)
				(type default)
			)
			(layer "B.Fab")
		)
		(fp_line
			(start -0.12065 -0.2794)
			(end -0.12065 -0.3048)
			(stroke
				(width 0.1)
				(type default)
			)
			(layer "B.Fab")
		)
		(fp_line
			(start 0.12065 -0.2794)
			(end -0.12065 -0.2794)
			(stroke
				(width 0.1)
				(type default)
			)
			(layer "B.Fab")
		)
		(fp_line
			(start -0.67945 -0.3048)
			(end -0.67945 0.3048)
			(stroke
				(width 0.1)
				(type default)
			)
			(layer "B.Fab")
		)
		(fp_line
			(start -0.12065 -0.3048)
			(end -0.67945 -0.3048)
			(stroke
				(width 0.1)
				(type default)
			)
			(layer "B.Fab")
		)
		(fp_line
			(start 0.12065 -0.305054)
			(end 0.12065 -0.2794)
			(stroke
				(width 0.1)
				(type default)
			)
			(layer "B.Fab")
		)
		(fp_line
			(start 0.67945 -0.305054)
			(end 0.12065 -0.305054)
			(stroke
				(width 0.1)
				(type default)
			)
			(layer "B.Fab")
		)
		(pad "1" smd circle
			(at 0.40005 0 90)
			(size 0 0)
			(layers "B.Cu" "B.Mask" "B.Paste")
			(net "P3V3_AUX")
		)
		(pad "2" smd circle
			(at -0.40005 0 90)
			(size 0 0)
			(layers "B.Cu" "B.Mask" "B.Paste")
			(net "CPU1_CORETYPE2")
		)
	)
	(footprint ""
		(layer "B.Cu")
		(at 340.845902 -396.393162 -90)
		(property "Reference" "C617"
			(at 0 0 90)
			(layer "B.SilkS")
			(hide yes)
			(effects
				(font
					(size 1.27 1.27)
				)
				(justify mirror)
			)
		)
		(property "Value" ""
			(at 0 0 90)
			(layer "B.Fab")
			(effects
				(font
					(size 1.27 1.27)
				)
				(justify mirror)
			)
		)
		(duplicate_pad_numbers_are_jumpers no)
		(fp_line
			(start -0.299974 0.150114)
			(end 0.299974 0.150114)
			(stroke
				(width 0.1)
				(type default)
			)
			(layer "B.Fab")
		)
		(fp_line
			(start 0.299974 0.150114)
			(end 0.299974 -0.150114)
			(stroke
				(width 0.1)
				(type default)
			)
			(layer "B.Fab")
		)
		(fp_line
			(start -0.299974 -0.150114)
			(end -0.299974 0.150114)
			(stroke
				(width 0.1)
				(type default)
			)
			(layer "B.Fab")
		)
		(fp_line
			(start 0.299974 -0.150114)
			(end -0.299974 -0.150114)
			(stroke
				(width 0.1)
				(type default)
			)
			(layer "B.Fab")
		)
		(pad "1" smd rect
			(at 0.2667 0 90)
			(size 0.3048 0.381)
			(layers "B.Cu" "B.Mask" "B.Paste")
			(net "P0V9_CPU0_RT1_2A_2D")
		)
		(pad "2" smd rect
			(at -0.2667 0 90)
			(size 0.3048 0.381)
			(layers "B.Cu" "B.Mask" "B.Paste")
			(net "GND")
		)
	)
)
